(kicad_pcb
	(version 20260206)
	(generator "pcbnew")
	(generator_version "10.0")
	(general
		(thickness 1.6)
		(legacy_teardrops no)
	)
	(paper "A4")
	(title_block
		(title "04192023_DAF0TMB3IC0_F0TG_MB_C_brd_V02_OCP.brd")
		(comment 1 "Grand Teton / footprint 2783 of 8354 (U26), pads 5560-5670 of 6102")
	)
	(layers
		(0 "F.Cu" signal "TOP")
		(4 "In1.Cu" signal "GND")
		(6 "In2.Cu" signal "IN1")
		(8 "In3.Cu" signal "GND1")
		(10 "In4.Cu" signal "IN2")
		(12 "In5.Cu" signal "GND2")
		(14 "In6.Cu" signal "IN3")
		(16 "In7.Cu" signal "GND3")
		(18 "In8.Cu" signal "VCC")
		(20 "In9.Cu" signal "VCC1")
		(22 "In10.Cu" signal "GND4")
		(24 "In11.Cu" signal "IN4")
		(26 "In12.Cu" signal "GND5")
		(28 "In13.Cu" signal "IN5")
		(30 "In14.Cu" signal "GND6")
		(32 "In15.Cu" signal "IN6")
		(34 "In16.Cu" signal "GND7")
		(2 "B.Cu" signal "BOTTOM")
		(9 "F.Adhes" user "F.Adhesive")
		(11 "B.Adhes" user "B.Adhesive")
		(13 "F.Paste" user "Package Geometry/Pastemask Top")
		(15 "B.Paste" user "Package Geometry/Pastemask Bottom")
		(5 "F.SilkS" user "Ref Des/Silkscreen Top")
		(7 "B.SilkS" user "Ref Des/Silkscreen Bottom")
		(1 "F.Mask" user "Board Geometry/Soldermask Top")
		(3 "B.Mask" user "Board Geometry/Soldermask Bottom")
		(17 "Dwgs.User" user "User.Drawings")
		(19 "Cmts.User" user "User.Comments")
		(21 "Eco1.User" user "User.Eco1")
		(23 "Eco2.User" user "User.Eco2")
		(25 "Edge.Cuts" user "Board Geometry/Outline")
		(27 "Margin" user)
		(31 "F.CrtYd" user "Package Geometry/Place Bound Top")
		(29 "B.CrtYd" user "Package Geometry/Place Bound Bottom")
		(35 "F.Fab" user "Ref Des/Assembly Top")
		(33 "B.Fab" user "Ref Des/Assembly Bottom")
	)
	(footprint ""
		(layer "F.Cu")
		(at 111.927894 -258.880356 180)
		(property "Reference" "U26"
			(at -45.05579 -61.794136 0)
			(unlocked yes)
			(layer "F.SilkS")
			(effects
				(font
					(size 0.7874 0.5842)
					(thickness 0.1524)
				)
			)
		)
		(property "Value" ""
			(at 0 0 180)
			(layer "F.Fab")
			(effects
				(font
					(size 1.27 1.27)
				)
			)
		)
		(duplicate_pad_numbers_are_jumpers no)
		(pad "N34" smd circle
			(at -3.139948 -27.090116 180)
			(size 0.450088 0.450088)
			(layers "F.Cu" "F.Mask" "F.Paste")
			(net "GND")
		)
		(pad "N35" smd circle
			(at -2.199894 -27.090116 180)
			(size 0.450088 0.450088)
			(layers "F.Cu" "F.Mask" "F.Paste")
			(net "PVDDCR_CPU0_P1")
		)
		(pad "N36" smd circle
			(at -1.260094 -27.090116 180)
			(size 0.450088 0.450088)
			(layers "F.Cu" "F.Mask" "F.Paste")
			(net "PVDDCR_CPU0_P1")
		)
		(pad "N40" smd circle
			(at 1.560068 -27.090116 180)
			(size 0.450088 0.450088)
			(layers "F.Cu" "F.Mask" "F.Paste")
			(net "PVDDCR_CPU0_P1")
		)
		(pad "N41" smd circle
			(at 2.500122 -27.090116 180)
			(size 0.450088 0.450088)
			(layers "F.Cu" "F.Mask" "F.Paste")
			(net "PVDDCR_CPU0_P1")
		)
		(pad "N42" smd circle
			(at 3.439922 -27.090116 180)
			(size 0.450088 0.450088)
			(layers "F.Cu" "F.Mask" "F.Paste")
			(net "GND")
		)
		(pad "N43" smd circle
			(at 4.379976 -27.090116 180)
			(size 0.450088 0.450088)
			(layers "F.Cu" "F.Mask" "F.Paste")
			(net "P5E_CPU1_G1_RX_DN<4>")
		)
		(pad "N44" smd circle
			(at 5.32003 -27.090116 180)
			(size 0.450088 0.450088)
			(layers "F.Cu" "F.Mask" "F.Paste")
			(net "P5E_CPU1_G1_RX_DP<4>")
		)
		(pad "N45" smd circle
			(at 6.260084 -27.090116 180)
			(size 0.450088 0.450088)
			(layers "F.Cu" "F.Mask" "F.Paste")
			(net "GND")
		)
		(pad "N46" smd circle
			(at 7.199884 -27.090116 180)
			(size 0.450088 0.450088)
			(layers "F.Cu" "F.Mask" "F.Paste")
			(net "P5E_CPU1_G1_RX_DN<7>")
		)
		(pad "N47" smd circle
			(at 8.139938 -27.090116 180)
			(size 0.450088 0.450088)
			(layers "F.Cu" "F.Mask" "F.Paste")
			(net "P5E_CPU1_G1_RX_DP<7>")
		)
		(pad "N48" smd circle
			(at 9.079992 -27.090116 180)
			(size 0.450088 0.450088)
			(layers "F.Cu" "F.Mask" "F.Paste")
			(net "GND")
		)
		(pad "N49" smd circle
			(at 10.020046 -27.090116 180)
			(size 0.450088 0.450088)
			(layers "F.Cu" "F.Mask" "F.Paste")
			(net "P5E_CPU1_G1_RX_DN<10>")
		)
		(pad "N50" smd circle
			(at 10.9601 -27.090116 180)
			(size 0.450088 0.450088)
			(layers "F.Cu" "F.Mask" "F.Paste")
			(net "P5E_CPU1_G1_RX_DP<10>")
		)
		(pad "N51" smd circle
			(at 11.8999 -27.090116 180)
			(size 0.450088 0.450088)
			(layers "F.Cu" "F.Mask" "F.Paste")
			(net "GND")
		)
		(pad "N52" smd circle
			(at 12.839954 -27.090116 180)
			(size 0.450088 0.450088)
			(layers "F.Cu" "F.Mask" "F.Paste")
			(net "GMI_CPU0_G2_CPU1_G0_TX_DN<0>")
		)
		(pad "N53" smd circle
			(at 13.780008 -27.090116 180)
			(size 0.450088 0.450088)
			(layers "F.Cu" "F.Mask" "F.Paste")
			(net "GMI_CPU0_G2_CPU1_G0_TX_DP<0>")
		)
		(pad "N54" smd circle
			(at 14.720062 -27.090116 180)
			(size 0.450088 0.450088)
			(layers "F.Cu" "F.Mask" "F.Paste")
			(net "GND")
		)
		(pad "N55" smd circle
			(at 15.660116 -27.090116 180)
			(size 0.450088 0.450088)
			(layers "F.Cu" "F.Mask" "F.Paste")
			(net "M_C_CPU1_SA_DQ<11>")
		)
		(pad "N56" smd circle
			(at 16.599916 -27.090116 180)
			(size 0.450088 0.450088)
			(layers "F.Cu" "F.Mask" "F.Paste")
			(net "GND")
		)
		(pad "N57" smd circle
			(at 17.53997 -27.090116 180)
			(size 0.450088 0.450088)
			(layers "F.Cu" "F.Mask" "F.Paste")
			(net "M_C_CPU1_SA_DQS_DP<1>")
		)
		(pad "N58" smd circle
			(at 18.480024 -27.090116 180)
			(size 0.450088 0.450088)
			(layers "F.Cu" "F.Mask" "F.Paste")
			(net "GND")
		)
		(pad "N59" smd circle
			(at 19.420078 -27.090116 180)
			(size 0.450088 0.450088)
			(layers "F.Cu" "F.Mask" "F.Paste")
			(net "M_D_CPU1_SA_DQ<11>")
		)
		(pad "N60" smd circle
			(at 20.359878 -27.090116 180)
			(size 0.450088 0.450088)
			(layers "F.Cu" "F.Mask" "F.Paste")
			(net "M_D_CPU1_SA_DQS_DP<1>")
		)
		(pad "N61" smd circle
			(at 21.299932 -27.090116 180)
			(size 0.450088 0.450088)
			(layers "F.Cu" "F.Mask" "F.Paste")
			(net "GND")
		)
		(pad "N62" smd circle
			(at 22.239986 -27.090116 180)
			(size 0.450088 0.450088)
			(layers "F.Cu" "F.Mask" "F.Paste")
			(net "M_B_CPU1_SA_DQ<11>")
		)
		(pad "N63" smd circle
			(at 23.18004 -27.090116 180)
			(size 0.450088 0.450088)
			(layers "F.Cu" "F.Mask" "F.Paste")
			(net "GND")
		)
		(pad "N64" smd circle
			(at 24.120094 -27.090116 180)
			(size 0.450088 0.450088)
			(layers "F.Cu" "F.Mask" "F.Paste")
			(net "M_B_CPU1_SA_DQS_DP<1>")
		)
		(pad "N65" smd circle
			(at 25.059894 -27.090116 180)
			(size 0.450088 0.450088)
			(layers "F.Cu" "F.Mask" "F.Paste")
			(net "GND")
		)
		(pad "N66" smd circle
			(at 25.999948 -27.090116 180)
			(size 0.450088 0.450088)
			(layers "F.Cu" "F.Mask" "F.Paste")
			(net "M_F_CPU1_SA_DQ<11>")
		)
		(pad "N67" smd circle
			(at 26.940002 -27.090116 180)
			(size 0.450088 0.450088)
			(layers "F.Cu" "F.Mask" "F.Paste")
			(net "M_F_CPU1_SA_DQS_DP<1>")
		)
		(pad "N68" smd circle
			(at 27.880056 -27.090116 180)
			(size 0.450088 0.450088)
			(layers "F.Cu" "F.Mask" "F.Paste")
			(net "GND")
		)
		(pad "N69" smd circle
			(at 28.82011 -27.090116 180)
			(size 0.450088 0.450088)
			(layers "F.Cu" "F.Mask" "F.Paste")
			(net "M_E_CPU1_SA_DQ<11>")
		)
		(pad "N70" smd circle
			(at 29.75991 -27.090116 180)
			(size 0.450088 0.450088)
			(layers "F.Cu" "F.Mask" "F.Paste")
			(net "GND")
		)
		(pad "N71" smd circle
			(at 30.699964 -27.090116 180)
			(size 0.450088 0.450088)
			(layers "F.Cu" "F.Mask" "F.Paste")
			(net "M_E_CPU1_SA_DQS_DP<1>")
		)
		(pad "N72" smd circle
			(at 31.640018 -27.090116 180)
			(size 0.450088 0.450088)
			(layers "F.Cu" "F.Mask" "F.Paste")
			(net "GND")
		)
		(pad "N73" smd circle
			(at 32.580072 -27.090116 180)
			(size 0.450088 0.450088)
			(layers "F.Cu" "F.Mask" "F.Paste")
			(net "M_A_CPU1_SA_DQ<11>")
		)
		(pad "N74" smd circle
			(at 33.519872 -27.090116 180)
			(size 0.450088 0.450088)
			(layers "F.Cu" "F.Mask" "F.Paste")
			(net "M_A_CPU1_SA_DQS_DP<1>")
		)
		(pad "N75" smd circle
			(at 34.459926 -27.090116 180)
			(size 0.450088 0.450088)
			(layers "F.Cu" "F.Mask" "F.Paste")
			(net "GND")
		)
		(pad "P2" smd circle
			(at -33.690052 -26.28011 180)
			(size 0.450088 0.450088)
			(layers "F.Cu" "F.Mask" "F.Paste")
			(net "M_G_CPU1_SA_DQS_DN<1>")
		)
		(pad "P3" smd circle
			(at -32.749998 -26.28011 180)
			(size 0.450088 0.450088)
			(layers "F.Cu" "F.Mask" "F.Paste")
			(net "GND")
		)
		(pad "P4" smd circle
			(at -31.809944 -26.28011 180)
			(size 0.450088 0.450088)
			(layers "F.Cu" "F.Mask" "F.Paste")
			(net "M_G_CPU1_SA_DQS_DN<6>")
		)
		(pad "P5" smd circle
			(at -30.86989 -26.28011 180)
			(size 0.450088 0.450088)
			(layers "F.Cu" "F.Mask" "F.Paste")
			(net "PVDDCR_SOC_P1")
		)
		(pad "P6" smd circle
			(at -29.93009 -26.28011 180)
			(size 0.450088 0.450088)
			(layers "F.Cu" "F.Mask" "F.Paste")
			(net "M_K_CPU1_SA_DQS_DN<1>")
		)
		(pad "P7" smd circle
			(at -28.990036 -26.28011 180)
			(size 0.450088 0.450088)
			(layers "F.Cu" "F.Mask" "F.Paste")
			(net "M_K_CPU1_SA_DQS_DN<6>")
		)
		(pad "P8" smd circle
			(at -28.049982 -26.28011 180)
			(size 0.450088 0.450088)
			(layers "F.Cu" "F.Mask" "F.Paste")
			(net "GND")
		)
		(pad "P9" smd circle
			(at -27.109928 -26.28011 180)
			(size 0.450088 0.450088)
			(layers "F.Cu" "F.Mask" "F.Paste")
			(net "M_L_CPU1_SA_DQS_DN<1>")
		)
		(pad "P10" smd circle
			(at -26.170128 -26.28011 180)
			(size 0.450088 0.450088)
			(layers "F.Cu" "F.Mask" "F.Paste")
			(net "GND")
		)
		(pad "P11" smd circle
			(at -25.230074 -26.28011 180)
			(size 0.450088 0.450088)
			(layers "F.Cu" "F.Mask" "F.Paste")
			(net "M_L_CPU1_SA_DQS_DN<6>")
		)
		(pad "P12" smd circle
			(at -24.29002 -26.28011 180)
			(size 0.450088 0.450088)
			(layers "F.Cu" "F.Mask" "F.Paste")
			(net "PVDDCR_SOC_P1")
		)
		(pad "P13" smd circle
			(at -23.349966 -26.28011 180)
			(size 0.450088 0.450088)
			(layers "F.Cu" "F.Mask" "F.Paste")
			(net "M_H_CPU1_SA_DQS_DN<1>")
		)
		(pad "P14" smd circle
			(at -22.409912 -26.28011 180)
			(size 0.450088 0.450088)
			(layers "F.Cu" "F.Mask" "F.Paste")
			(net "M_H_CPU1_SA_DQS_DN<6>")
		)
		(pad "P15" smd circle
			(at -21.470112 -26.28011 180)
			(size 0.450088 0.450088)
			(layers "F.Cu" "F.Mask" "F.Paste")
			(net "GND")
		)
		(pad "P16" smd circle
			(at -20.530058 -26.28011 180)
			(size 0.450088 0.450088)
			(layers "F.Cu" "F.Mask" "F.Paste")
			(net "M_J_CPU1_SA_DQS_DN<1>")
		)
		(pad "P17" smd circle
			(at -19.590004 -26.28011 180)
			(size 0.450088 0.450088)
			(layers "F.Cu" "F.Mask" "F.Paste")
			(net "GND")
		)
		(pad "P18" smd circle
			(at -18.64995 -26.28011 180)
			(size 0.450088 0.450088)
			(layers "F.Cu" "F.Mask" "F.Paste")
			(net "M_J_CPU1_SA_DQS_DN<6>")
		)
		(pad "P19" smd circle
			(at -17.709896 -26.28011 180)
			(size 0.450088 0.450088)
			(layers "F.Cu" "F.Mask" "F.Paste")
			(net "PVDDCR_SOC_P1")
		)
		(pad "P20" smd circle
			(at -16.770096 -26.28011 180)
			(size 0.450088 0.450088)
			(layers "F.Cu" "F.Mask" "F.Paste")
			(net "M_I_CPU1_SA_DQS_DN<1>")
		)
		(pad "P21" smd circle
			(at -15.830042 -26.28011 180)
			(size 0.450088 0.450088)
			(layers "F.Cu" "F.Mask" "F.Paste")
			(net "M_I_CPU1_SA_DQS_DN<6>")
		)
		(pad "P22" smd circle
			(at -14.889988 -26.28011 180)
			(size 0.450088 0.450088)
			(layers "F.Cu" "F.Mask" "F.Paste")
			(net "PVDDCR_SOC_P1")
		)
		(pad "P23" smd circle
			(at -13.949934 -26.28011 180)
			(size 0.450088 0.450088)
			(layers "F.Cu" "F.Mask" "F.Paste")
			(net "GND")
		)
		(pad "P24" smd circle
			(at -13.00988 -26.28011 180)
			(size 0.450088 0.450088)
			(layers "F.Cu" "F.Mask" "F.Paste")
			(net "GND")
		)
		(pad "P25" smd circle
			(at -12.07008 -26.28011 180)
			(size 0.450088 0.450088)
			(layers "F.Cu" "F.Mask" "F.Paste")
			(net "GND")
		)
		(pad "P26" smd circle
			(at -11.130026 -26.28011 180)
			(size 0.450088 0.450088)
			(layers "F.Cu" "F.Mask" "F.Paste")
			(net "GND")
		)
		(pad "P27" smd circle
			(at -10.189972 -26.28011 180)
			(size 0.450088 0.450088)
			(layers "F.Cu" "F.Mask" "F.Paste")
			(net "GND")
		)
		(pad "P28" smd circle
			(at -9.249918 -26.28011 180)
			(size 0.450088 0.450088)
			(layers "F.Cu" "F.Mask" "F.Paste")
			(net "GND")
		)
		(pad "P29" smd circle
			(at -8.310118 -26.28011 180)
			(size 0.450088 0.450088)
			(layers "F.Cu" "F.Mask" "F.Paste")
			(net "GND")
		)
		(pad "P30" smd circle
			(at -7.370064 -26.28011 180)
			(size 0.450088 0.450088)
			(layers "F.Cu" "F.Mask" "F.Paste")
			(net "GND")
		)
		(pad "P31" smd circle
			(at -6.43001 -26.28011 180)
			(size 0.450088 0.450088)
			(layers "F.Cu" "F.Mask" "F.Paste")
			(net "GND")
		)
		(pad "P32" smd circle
			(at -5.489956 -26.28011 180)
			(size 0.450088 0.450088)
			(layers "F.Cu" "F.Mask" "F.Paste")
			(net "GND")
		)
		(pad "P33" smd circle
			(at -4.549902 -26.28011 180)
			(size 0.450088 0.450088)
			(layers "F.Cu" "F.Mask" "F.Paste")
			(net "GND")
		)
		(pad "P34" smd circle
			(at -3.610102 -26.28011 180)
			(size 0.450088 0.450088)
			(layers "F.Cu" "F.Mask" "F.Paste")
			(net "GND")
		)
		(pad "P35" smd circle
			(at -2.670048 -26.28011 180)
			(size 0.450088 0.450088)
			(layers "F.Cu" "F.Mask" "F.Paste")
			(net "GMI_CPU1_G3_CPU0_G1_TX_DP<2>")
		)
		(pad "P36" smd circle
			(at -1.729994 -26.28011 180)
			(size 0.450088 0.450088)
			(layers "F.Cu" "F.Mask" "F.Paste")
			(net "GMI_CPU1_G3_CPU0_G1_TX_DN<2>")
		)
		(pad "P37" smd circle
			(at -0.78994 -26.28011 180)
			(size 0.450088 0.450088)
			(layers "F.Cu" "F.Mask" "F.Paste")
			(net "GND")
		)
		(pad "P39" smd circle
			(at 1.089914 -26.28011 180)
			(size 0.450088 0.450088)
			(layers "F.Cu" "F.Mask" "F.Paste")
			(net "GND")
		)
		(pad "P40" smd circle
			(at 2.029968 -26.28011 180)
			(size 0.450088 0.450088)
			(layers "F.Cu" "F.Mask" "F.Paste")
			(net "P5E_CPU1_G1_RX_DN<2>")
		)
		(pad "P41" smd circle
			(at 2.970022 -26.28011 180)
			(size 0.450088 0.450088)
			(layers "F.Cu" "F.Mask" "F.Paste")
			(net "P5E_CPU1_G1_RX_DP<2>")
		)
		(pad "P42" smd circle
			(at 3.910076 -26.28011 180)
			(size 0.450088 0.450088)
			(layers "F.Cu" "F.Mask" "F.Paste")
			(net "GND")
		)
		(pad "P43" smd circle
			(at 4.849876 -26.28011 180)
			(size 0.450088 0.450088)
			(layers "F.Cu" "F.Mask" "F.Paste")
			(net "GND")
		)
		(pad "P44" smd circle
			(at 5.78993 -26.28011 180)
			(size 0.450088 0.450088)
			(layers "F.Cu" "F.Mask" "F.Paste")
			(net "GND")
		)
		(pad "P45" smd circle
			(at 6.729984 -26.28011 180)
			(size 0.450088 0.450088)
			(layers "F.Cu" "F.Mask" "F.Paste")
			(net "GND")
		)
		(pad "P46" smd circle
			(at 7.670038 -26.28011 180)
			(size 0.450088 0.450088)
			(layers "F.Cu" "F.Mask" "F.Paste")
			(net "GND")
		)
		(pad "P47" smd circle
			(at 8.610092 -26.28011 180)
			(size 0.450088 0.450088)
			(layers "F.Cu" "F.Mask" "F.Paste")
			(net "GND")
		)
		(pad "P48" smd circle
			(at 9.549892 -26.28011 180)
			(size 0.450088 0.450088)
			(layers "F.Cu" "F.Mask" "F.Paste")
			(net "GND")
		)
		(pad "P49" smd circle
			(at 10.489946 -26.28011 180)
			(size 0.450088 0.450088)
			(layers "F.Cu" "F.Mask" "F.Paste")
			(net "GND")
		)
		(pad "P50" smd circle
			(at 11.43 -26.28011 180)
			(size 0.450088 0.450088)
			(layers "F.Cu" "F.Mask" "F.Paste")
			(net "GND")
		)
		(pad "P51" smd circle
			(at 12.370054 -26.28011 180)
			(size 0.450088 0.450088)
			(layers "F.Cu" "F.Mask" "F.Paste")
			(net "GND")
		)
		(pad "P52" smd circle
			(at 13.310108 -26.28011 180)
			(size 0.450088 0.450088)
			(layers "F.Cu" "F.Mask" "F.Paste")
			(net "GND")
		)
		(pad "P53" smd circle
			(at 14.249908 -26.28011 180)
			(size 0.450088 0.450088)
			(layers "F.Cu" "F.Mask" "F.Paste")
			(net "GND")
		)
		(pad "P54" smd circle
			(at 15.189962 -26.28011 180)
			(size 0.450088 0.450088)
			(layers "F.Cu" "F.Mask" "F.Paste")
			(net "PVDDIO_P1")
		)
		(pad "P55" smd circle
			(at 16.130016 -26.28011 180)
			(size 0.450088 0.450088)
			(layers "F.Cu" "F.Mask" "F.Paste")
			(net "M_C_CPU1_SA_DQS_DN<6>")
		)
		(pad "P56" smd circle
			(at 17.07007 -26.28011 180)
			(size 0.450088 0.450088)
			(layers "F.Cu" "F.Mask" "F.Paste")
			(net "M_C_CPU1_SA_DQS_DN<1>")
		)
		(pad "P57" smd circle
			(at 18.010124 -26.28011 180)
			(size 0.450088 0.450088)
			(layers "F.Cu" "F.Mask" "F.Paste")
			(net "PVDDIO_P1")
		)
		(pad "P58" smd circle
			(at 18.949924 -26.28011 180)
			(size 0.450088 0.450088)
			(layers "F.Cu" "F.Mask" "F.Paste")
			(net "M_D_CPU1_SA_DQS_DN<6>")
		)
		(pad "P59" smd circle
			(at 19.889978 -26.28011 180)
			(size 0.450088 0.450088)
			(layers "F.Cu" "F.Mask" "F.Paste")
			(net "GND")
		)
		(pad "P60" smd circle
			(at 20.830032 -26.28011 180)
			(size 0.450088 0.450088)
			(layers "F.Cu" "F.Mask" "F.Paste")
			(net "M_D_CPU1_SA_DQS_DN<1>")
		)
		(pad "P61" smd circle
			(at 21.770086 -26.28011 180)
			(size 0.450088 0.450088)
			(layers "F.Cu" "F.Mask" "F.Paste")
			(net "GND")
		)
		(pad "P62" smd circle
			(at 22.709886 -26.28011 180)
			(size 0.450088 0.450088)
			(layers "F.Cu" "F.Mask" "F.Paste")
			(net "M_B_CPU1_SA_DQS_DN<6>")
		)
		(pad "P63" smd circle
			(at 23.64994 -26.28011 180)
			(size 0.450088 0.450088)
			(layers "F.Cu" "F.Mask" "F.Paste")
			(net "M_B_CPU1_SA_DQS_DN<1>")
		)
		(pad "P64" smd circle
			(at 24.589994 -26.28011 180)
			(size 0.450088 0.450088)
			(layers "F.Cu" "F.Mask" "F.Paste")
			(net "PVDDIO_P1")
		)
		(pad "P65" smd circle
			(at 25.530048 -26.28011 180)
			(size 0.450088 0.450088)
			(layers "F.Cu" "F.Mask" "F.Paste")
			(net "M_F_CPU1_SA_DQS_DN<6>")
		)
		(pad "P66" smd circle
			(at 26.470102 -26.28011 180)
			(size 0.450088 0.450088)
			(layers "F.Cu" "F.Mask" "F.Paste")
			(net "GND")
		)
		(pad "P67" smd circle
			(at 27.409902 -26.28011 180)
			(size 0.450088 0.450088)
			(layers "F.Cu" "F.Mask" "F.Paste")
			(net "M_F_CPU1_SA_DQS_DN<1>")
		)
		(pad "P68" smd circle
			(at 28.349956 -26.28011 180)
			(size 0.450088 0.450088)
			(layers "F.Cu" "F.Mask" "F.Paste")
			(net "GND")
		)
		(pad "P69" smd circle
			(at 29.29001 -26.28011 180)
			(size 0.450088 0.450088)
			(layers "F.Cu" "F.Mask" "F.Paste")
			(net "M_E_CPU1_SA_DQS_DN<6>")
		)
		(pad "P70" smd circle
			(at 30.230064 -26.28011 180)
			(size 0.450088 0.450088)
			(layers "F.Cu" "F.Mask" "F.Paste")
			(net "M_E_CPU1_SA_DQS_DN<1>")
		)
		(pad "P71" smd circle
			(at 31.170118 -26.28011 180)
			(size 0.450088 0.450088)
			(layers "F.Cu" "F.Mask" "F.Paste")
			(net "PVDDIO_P1")
		)
		(pad "P72" smd circle
			(at 32.109918 -26.28011 180)
			(size 0.450088 0.450088)
			(layers "F.Cu" "F.Mask" "F.Paste")
			(net "M_A_CPU1_SA_DQS_DN<6>")
		)
		(pad "P73" smd circle
			(at 33.049972 -26.28011 180)
			(size 0.450088 0.450088)
			(layers "F.Cu" "F.Mask" "F.Paste")
			(net "GND")
		)
		(pad "P74" smd circle
			(at 33.990026 -26.28011 180)
			(size 0.450088 0.450088)
			(layers "F.Cu" "F.Mask" "F.Paste")
			(net "M_A_CPU1_SA_DQS_DN<1>")
		)
	)
)
